# T6G (Grand Teton) — schematic netlist excerpt (pin names and nets, part order shuffled) for the footprints in the layout excerpt that follows; sources: Cadence DE-HDL packaged netlist, KiCad conversion of 04192023_DAF0TMB3IC0_F0TG_MB_C_brd_V02_OCP.brd

R3571  Q_RES  10 1% CHIP  pkg 0402LF  page 237 : A = P3V3_OCP_V3_2 ; B = VSENSE_P12V_INA230_3_INN
PR520  Q_RES  1.5 1% EMPTY  pkg 0402LF  page 225 : A = SW_PVDD11_S3_P1_SW1_RC ; B = GND

(kicad_pcb
	(version 20260206)
	(generator "pcbnew")
	(generator_version "10.0")
	(general
		(thickness 1.6)
		(legacy_teardrops no)
	)
	(paper "A4")
	(title_block
		(title "04192023_DAF0TMB3IC0_F0TG_MB_C_brd_V02_OCP.brd")
		(comment 1 "Grand Teton / footprints 2222-2223 of 8354")
	)
	(layers
		(0 "F.Cu" signal "TOP")
		(4 "In1.Cu" signal "GND")
		(6 "In2.Cu" signal "IN1")
		(8 "In3.Cu" signal "GND1")
		(10 "In4.Cu" signal "IN2")
		(12 "In5.Cu" signal "GND2")
		(14 "In6.Cu" signal "IN3")
		(16 "In7.Cu" signal "GND3")
		(18 "In8.Cu" signal "VCC")
		(20 "In9.Cu" signal "VCC1")
		(22 "In10.Cu" signal "GND4")
		(24 "In11.Cu" signal "IN4")
		(26 "In12.Cu" signal "GND5")
		(28 "In13.Cu" signal "IN5")
		(30 "In14.Cu" signal "GND6")
		(32 "In15.Cu" signal "IN6")
		(34 "In16.Cu" signal "GND7")
		(2 "B.Cu" signal "BOTTOM")
		(9 "F.Adhes" user "F.Adhesive")
		(11 "B.Adhes" user "B.Adhesive")
		(13 "F.Paste" user "Package Geometry/Pastemask Top")
		(15 "B.Paste" user "Package Geometry/Pastemask Bottom")
		(5 "F.SilkS" user "Ref Des/Silkscreen Top")
		(7 "B.SilkS" user "Ref Des/Silkscreen Bottom")
		(1 "F.Mask" user "Board Geometry/Soldermask Top")
		(3 "B.Mask" user "Board Geometry/Soldermask Bottom")
		(17 "Dwgs.User" user "User.Drawings")
		(19 "Cmts.User" user "User.Comments")
		(21 "Eco1.User" user "User.Eco1")
		(23 "Eco2.User" user "User.Eco2")
		(25 "Edge.Cuts" user "Board Geometry/Outline")
		(27 "Margin" user)
		(31 "F.CrtYd" user "Package Geometry/Place Bound Top")
		(29 "B.CrtYd" user "Package Geometry/Place Bound Bottom")
		(35 "F.Fab" user "Ref Des/Assembly Top")
		(33 "B.Fab" user "Ref Des/Assembly Bottom")
	)
	(footprint ""
		(layer "F.Cu")
		(at 179.24272 -349.56115 90)
		(property "Reference" "PR520"
			(at 0 0 90)
			(layer "F.SilkS")
			(hide yes)
			(effects
				(font
					(size 1.27 1.27)
				)
			)
		)
		(property "Value" ""
			(at 0 0 90)
			(layer "F.Fab")
			(effects
				(font
					(size 1.27 1.27)
				)
			)
		)
		(duplicate_pad_numbers_are_jumpers no)
		(fp_line
			(start 0.7874 -0.4064)
			(end 0.7874 0.4064)
			(stroke
				(width 0.1524)
				(type default)
			)
			(layer "F.SilkS")
		)
		(fp_line
			(start -0.7874 -0.4064)
			(end 0.7874 -0.4064)
			(stroke
				(width 0.1524)
				(type default)
			)
			(layer "F.SilkS")
		)
		(fp_line
			(start 0.7874 0.4064)
			(end -0.7874 0.4064)
			(stroke
				(width 0.1524)
				(type default)
			)
			(layer "F.SilkS")
		)
		(fp_line
			(start -0.7874 0.4064)
			(end -0.7874 -0.4064)
			(stroke
				(width 0.1524)
				(type default)
			)
			(layer "F.SilkS")
		)
		(fp_line
			(start -0.12065 -0.305054)
			(end -0.12065 -0.2794)
			(stroke
				(width 0.1)
				(type default)
			)
			(layer "F.Fab")
		)
		(fp_line
			(start -0.67945 -0.305054)
			(end -0.12065 -0.305054)
			(stroke
				(width 0.1)
				(type default)
			)
			(layer "F.Fab")
		)
		(fp_line
			(start 0.67945 -0.3048)
			(end 0.67945 0.3048)
			(stroke
				(width 0.1)
				(type default)
			)
			(layer "F.Fab")
		)
		(fp_line
			(start 0.12065 -0.3048)
			(end 0.67945 -0.3048)
			(stroke
				(width 0.1)
				(type default)
			)
			(layer "F.Fab")
		)
		(fp_line
			(start 0.12065 -0.2794)
			(end 0.12065 -0.3048)
			(stroke
				(width 0.1)
				(type default)
			)
			(layer "F.Fab")
		)
		(fp_line
			(start -0.12065 -0.2794)
			(end 0.12065 -0.2794)
			(stroke
				(width 0.1)
				(type default)
			)
			(layer "F.Fab")
		)
		(fp_line
			(start 0.120396 0.2794)
			(end -0.12065 0.2794)
			(stroke
				(width 0.1)
				(type default)
			)
			(layer "F.Fab")
		)
		(fp_line
			(start -0.12065 0.2794)
			(end -0.12065 0.3048)
			(stroke
				(width 0.1)
				(type default)
			)
			(layer "F.Fab")
		)
		(fp_line
			(start 0.67945 0.3048)
			(end 0.120396 0.3048)
			(stroke
				(width 0.1)
				(type default)
			)
			(layer "F.Fab")
		)
		(fp_line
			(start 0.120396 0.3048)
			(end 0.120396 0.2794)
			(stroke
				(width 0.1)
				(type default)
			)
			(layer "F.Fab")
		)
		(fp_line
			(start -0.12065 0.3048)
			(end -0.67945 0.3048)
			(stroke
				(width 0.1)
				(type default)
			)
			(layer "F.Fab")
		)
		(fp_line
			(start -0.67945 0.3048)
			(end -0.67945 -0.305054)
			(stroke
				(width 0.1)
				(type default)
			)
			(layer "F.Fab")
		)
		(pad "1" smd circle
			(at -0.40005 0 90)
			(size 0 0)
			(layers "F.Cu" "F.Mask" "F.Paste")
			(net "SW_PVDD11_S3_P1_SW1_RC")
		)
		(pad "2" smd circle
			(at 0.40005 0 90)
			(size 0 0)
			(layers "F.Cu" "F.Mask" "F.Paste")
			(net "GND")
		)
	)
	(footprint ""
		(layer "F.Cu")
		(at 80.223106 -57.874154 180)
		(property "Reference" "R3571"
			(at 0 0 180)
			(layer "F.SilkS")
			(hide yes)
			(effects
				(font
					(size 1.27 1.27)
				)
			)
		)
		(property "Value" ""
			(at 0 0 180)
			(layer "F.Fab")
			(effects
				(font
					(size 1.27 1.27)
				)
			)
		)
		(duplicate_pad_numbers_are_jumpers no)
		(fp_line
			(start 0.7874 0.4064)
			(end -0.7874 0.4064)
			(stroke
				(width 0.1524)
				(type default)
			)
			(layer "F.SilkS")
		)
		(fp_line
			(start 0.7874 -0.4064)
			(end 0.7874 0.4064)
			(stroke
				(width 0.1524)
				(type default)
			)
			(layer "F.SilkS")
		)
		(fp_line
			(start -0.7874 0.4064)
			(end -0.7874 -0.4064)
			(stroke
				(width 0.1524)
				(type default)
			)
			(layer "F.SilkS")
		)
		(fp_line
			(start -0.7874 -0.4064)
			(end 0.7874 -0.4064)
			(stroke
				(width 0.1524)
				(type default)
			)
			(layer "F.SilkS")
		)
		(fp_line
			(start 0.67945 0.3048)
			(end 0.120396 0.3048)
			(stroke
				(width 0.1)
				(type default)
			)
			(layer "F.Fab")
		)
		(fp_line
			(start 0.67945 -0.3048)
			(end 0.67945 0.3048)
			(stroke
				(width 0.1)
				(type default)
			)
			(layer "F.Fab")
		)
		(fp_line
			(start 0.12065 -0.2794)
			(end 0.12065 -0.3048)
			(stroke
				(width 0.1)
				(type default)
			)
			(layer "F.Fab")
		)
		(fp_line
			(start 0.12065 -0.3048)
			(end 0.67945 -0.3048)
			(stroke
				(width 0.1)
				(type default)
			)
			(layer "F.Fab")
		)
		(fp_line
			(start 0.120396 0.3048)
			(end 0.120396 0.2794)
			(stroke
				(width 0.1)
				(type default)
			)
			(layer "F.Fab")
		)
		(fp_line
			(start 0.120396 0.2794)
			(end -0.12065 0.2794)
			(stroke
				(width 0.1)
				(type default)
			)
			(layer "F.Fab")
		)
		(fp_line
			(start -0.12065 0.3048)
			(end -0.67945 0.3048)
			(stroke
				(width 0.1)
				(type default)
			)
			(layer "F.Fab")
		)
		(fp_line
			(start -0.12065 0.2794)
			(end -0.12065 0.3048)
			(stroke
				(width 0.1)
				(type default)
			)
			(layer "F.Fab")
		)
		(fp_line
			(start -0.12065 -0.2794)
			(end 0.12065 -0.2794)
			(stroke
				(width 0.1)
				(type default)
			)
			(layer "F.Fab")
		)
		(fp_line
			(start -0.12065 -0.305054)
			(end -0.12065 -0.2794)
			(stroke
				(width 0.1)
				(type default)
			)
			(layer "F.Fab")
		)
		(fp_line
			(start -0.67945 0.3048)
			(end -0.67945 -0.305054)
			(stroke
				(width 0.1)
				(type default)
			)
			(layer "F.Fab")
		)
		(fp_line
			(start -0.67945 -0.305054)
			(end -0.12065 -0.305054)
			(stroke
				(width 0.1)
				(type default)
			)
			(layer "F.Fab")
		)
		(pad "1" smd circle
			(at -0.40005 0 180)
			(size 0 0)
			(layers "F.Cu" "F.Mask" "F.Paste")
			(net "P3V3_OCP_V3_2")
		)
		(pad "2" smd circle
			(at 0.40005 0 180)
			(size 0 0)
			(layers "F.Cu" "F.Mask" "F.Paste")
			(net "VSENSE_P12V_INA230_3_INN")
		)
	)
)
